(kicad_pcb
	(version 20241229)
	(generator "pcbnew")
	(generator_version "9.0")
	(general
		(thickness 1.294)
		(legacy_teardrops no)
	)
	(paper "A3")
	(title_block
		(title "Kintex 410T devboard")
		(date "2024-04-03")
		(rev "1.1.2")
		(comment 9 "footprints 853-858 of 975")
	)
	(layers
		(0 "F.Cu" mixed)
		(4 "In1.Cu" power)
		(6 "In2.Cu" power)
		(8 "In3.Cu" mixed)
		(10 "In4.Cu" power)
		(12 "In5.Cu" mixed)
		(14 "In6.Cu" power)
		(16 "In7.Cu" mixed)
		(18 "In8.Cu" power)
		(2 "B.Cu" mixed)
		(9 "F.Adhes" user "F.Adhesive")
		(11 "B.Adhes" user "B.Adhesive")
		(13 "F.Paste" user)
		(15 "B.Paste" user)
		(5 "F.SilkS" user "F.Silkscreen")
		(7 "B.SilkS" user "B.Silkscreen")
		(1 "F.Mask" user)
		(3 "B.Mask" user)
		(17 "Dwgs.User" user "User.Drawings")
		(19 "Cmts.User" user "User.Comments")
		(21 "Eco1.User" user "User.Eco1")
		(23 "Eco2.User" user "User.Eco2")
		(25 "Edge.Cuts" user)
		(27 "Margin" user)
		(31 "F.CrtYd" user "F.Courtyard")
		(29 "B.CrtYd" user "B.Courtyard")
		(35 "F.Fab" user)
		(33 "B.Fab" user)
	)
	(footprint "antmicro-footprints:C_0402_1005Metric"
		(layer "B.Cu")
		(at 189.9 133.275 180)
		(descr "Capacitor SMD 0402")
		(tags "capacitor SMD 0402")
		(property "Reference" "C143"
			(at 1.025 -1.675 0)
			(layer "B.SilkS")
			(effects
				(font
					(size 0.7 0.7)
					(thickness 0.15)
				)
				(justify left bottom mirror)
			)
		)
		(property "Value" "C_100n_0402"
			(at 0 -1.169 0)
			(layer "B.Fab")
			(effects
				(font
					(size 0.7 0.7)
					(thickness 0.15)
				)
				(justify left bottom mirror)
			)
		)
		(property "Description" "SMD Multilayer Ceramic Capacitor, 0.1 µF, 50 V, 0402 [1005 Metric], ± 10%, X5R, GRM Series"
			(at 0 0 180)
			(layer "F.Fab")
			(hide yes)
			(effects
				(font
					(size 1.27 1.27)
					(thickness 0.15)
				)
			)
		)
		(property "Author" "Antmicro"
			(at 379.8 266.55 0)
			(layer "B.Fab")
			(hide yes)
			(effects
				(font
					(size 1 1)
					(thickness 0.15)
				)
				(justify mirror)
			)
		)
		(property "Dielectric" "X5R"
			(at 379.8 266.55 0)
			(layer "B.Fab")
			(hide yes)
			(effects
				(font
					(size 1 1)
					(thickness 0.15)
				)
				(justify mirror)
			)
		)
		(property "License" "Apache-2.0"
			(at 379.8 266.55 0)
			(layer "B.Fab")
			(hide yes)
			(effects
				(font
					(size 1 1)
					(thickness 0.15)
				)
				(justify mirror)
			)
		)
		(property "MPN" "GRM155R61H104KE14D"
			(at 379.8 266.55 0)
			(layer "B.Fab")
			(hide yes)
			(effects
				(font
					(size 1 1)
					(thickness 0.15)
				)
				(justify mirror)
			)
		)
		(property "Manufacturer" "Murata"
			(at 379.8 266.55 0)
			(layer "B.Fab")
			(hide yes)
			(effects
				(font
					(size 1 1)
					(thickness 0.15)
				)
				(justify mirror)
			)
		)
		(property "Val" "100n"
			(at 379.8 266.55 0)
			(layer "B.Fab")
			(hide yes)
			(effects
				(font
					(size 1 1)
					(thickness 0.15)
				)
				(justify mirror)
			)
		)
		(property "Voltage" "50V"
			(at 379.8 266.55 0)
			(layer "B.Fab")
			(hide yes)
			(effects
				(font
					(size 1 1)
					(thickness 0.15)
				)
				(justify mirror)
			)
		)
		(sheetname "FPGA supply")
		(sheetfile "fpga-supply.kicad_sch")
		(attr smd)
		(fp_rect
			(start -0.925 0.47)
			(end 0.925 -0.47)
			(stroke
				(width 0.05)
				(type default)
			)
			(fill no)
			(layer "B.CrtYd")
		)
		(fp_line
			(start 0.504 0.25)
			(end 0.504 -0.248)
			(stroke
				(width 0.15)
				(type solid)
			)
			(layer "B.Fab")
		)
		(fp_line
			(start 0.504 -0.248)
			(end -0.494 -0.248)
			(stroke
				(width 0.15)
				(type solid)
			)
			(layer "B.Fab")
		)
		(fp_line
			(start -0.494 0.25)
			(end 0.504 0.25)
			(stroke
				(width 0.15)
				(type solid)
			)
			(layer "B.Fab")
		)
		(fp_line
			(start -0.494 -0.248)
			(end -0.494 0.25)
			(stroke
				(width 0.15)
				(type solid)
			)
			(layer "B.Fab")
		)
		(pad "1" smd roundrect
			(at -0.48 0 180)
			(size 0.59 0.64)
			(layers "B.Cu" "B.Mask" "B.Paste")
			(roundrect_rratio 0.25)
			(net 1 "GND")
			(pintype "passive")
		)
		(pad "2" smd roundrect
			(at 0.48 0 180)
			(size 0.59 0.64)
			(layers "B.Cu" "B.Mask" "B.Paste")
			(roundrect_rratio 0.25)
			(net 8 "+1V2_MGTAVTT")
			(pintype "passive")
		)
	)
	(footprint "antmicro-footprints:C_0402_1005Metric"
		(layer "B.Cu")
		(at 160.5 144.525 -90)
		(descr "Capacitor SMD 0402")
		(tags "capacitor SMD 0402")
		(property "Reference" "C169"
			(at -1.9 3.475 90)
			(layer "B.SilkS")
			(effects
				(font
					(size 0.7 0.7)
					(thickness 0.15)
				)
				(justify left bottom mirror)
			)
		)
		(property "Value" "C_10u_0402"
			(at 0 -1.4 90)
			(layer "B.Fab")
			(effects
				(font
					(size 0.7 0.7)
					(thickness 0.15)
				)
				(justify left bottom mirror)
			)
		)
		(property "Description" "SMD Multilayer Ceramic Capacitor, 10 µF, 6.3 V, 0402 [1005 Metric], ± 20%, X5R, CC Series"
			(at 0 0 270)
			(layer "F.Fab")
			(hide yes)
			(effects
				(font
					(size 1.27 1.27)
					(thickness 0.15)
				)
			)
		)
		(property "Author" "Antmicro"
			(at 15.975 305.025 0)
			(layer "B.Fab")
			(hide yes)
			(effects
				(font
					(size 1 1)
					(thickness 0.15)
				)
				(justify mirror)
			)
		)
		(property "Dielectric" ""
			(at 15.975 305.025 0)
			(layer "B.Fab")
			(hide yes)
			(effects
				(font
					(size 1 1)
					(thickness 0.15)
				)
				(justify mirror)
			)
		)
		(property "License" "Apache-2.0"
			(at 15.975 305.025 0)
			(layer "B.Fab")
			(hide yes)
			(effects
				(font
					(size 1 1)
					(thickness 0.15)
				)
				(justify mirror)
			)
		)
		(property "MPN" "CC0402MRX5R5BB106"
			(at 15.975 305.025 0)
			(layer "B.Fab")
			(hide yes)
			(effects
				(font
					(size 1 1)
					(thickness 0.15)
				)
				(justify mirror)
			)
		)
		(property "Manufacturer" "YAGEO"
			(at 15.975 305.025 0)
			(layer "B.Fab")
			(hide yes)
			(effects
				(font
					(size 1 1)
					(thickness 0.15)
				)
				(justify mirror)
			)
		)
		(property "Val" "10u"
			(at 15.975 305.025 0)
			(layer "B.Fab")
			(hide yes)
			(effects
				(font
					(size 1 1)
					(thickness 0.15)
				)
				(justify mirror)
			)
		)
		(property "Voltage" ""
			(at 15.975 305.025 0)
			(layer "B.Fab")
			(hide yes)
			(effects
				(font
					(size 1 1)
					(thickness 0.15)
				)
				(justify mirror)
			)
		)
		(sheetname "DRAM + SRAM")
		(sheetfile "ram.kicad_sch")
		(attr smd)
		(fp_rect
			(start -0.925 0.47)
			(end 0.925 -0.47)
			(stroke
				(width 0.05)
				(type default)
			)
			(fill no)
			(layer "B.CrtYd")
		)
		(fp_line
			(start -0.494 0.25)
			(end 0.504 0.25)
			(stroke
				(width 0.15)
				(type solid)
			)
			(layer "B.Fab")
		)
		(fp_line
			(start 0.504 0.25)
			(end 0.504 -0.248)
			(stroke
				(width 0.15)
				(type solid)
			)
			(layer "B.Fab")
		)
		(fp_line
			(start -0.494 -0.248)
			(end -0.494 0.25)
			(stroke
				(width 0.15)
				(type solid)
			)
			(layer "B.Fab")
		)
		(fp_line
			(start 0.504 -0.248)
			(end -0.494 -0.248)
			(stroke
				(width 0.15)
				(type solid)
			)
			(layer "B.Fab")
		)
		(pad "1" smd roundrect
			(at -0.48 0 270)
			(size 0.59 0.64)
			(layers "B.Cu" "B.Mask" "B.Paste")
			(roundrect_rratio 0.25)
			(net 1 "GND")
			(pintype "passive")
		)
		(pad "2" smd roundrect
			(at 0.48 0 270)
			(size 0.59 0.64)
			(layers "B.Cu" "B.Mask" "B.Paste")
			(roundrect_rratio 0.25)
			(net 7 "+0V675_VTT")
			(pintype "passive")
		)
	)
	(footprint "antmicro-footprints:C_0402_1005Metric"
		(layer "B.Cu")
		(at 197 135.5 180)
		(descr "Capacitor SMD 0402")
		(tags "capacitor SMD 0402")
		(property "Reference" "C70"
			(at -25.15 28.025 0)
			(layer "B.SilkS")
			(effects
				(font
					(size 0.7 0.7)
					(thickness 0.15)
				)
				(justify left bottom mirror)
			)
		)
		(property "Value" "C_100n_0402"
			(at 0 -1.169 0)
			(layer "B.Fab")
			(effects
				(font
					(size 0.7 0.7)
					(thickness 0.15)
				)
				(justify left bottom mirror)
			)
		)
		(property "Description" "SMD Multilayer Ceramic Capacitor, 0.1 µF, 50 V, 0402 [1005 Metric], ± 10%, X5R, GRM Series"
			(at 0 0 180)
			(layer "F.Fab")
			(hide yes)
			(effects
				(font
					(size 1.27 1.27)
					(thickness 0.15)
				)
			)
		)
		(property "Author" "Antmicro"
			(at 394 271 0)
			(layer "B.Fab")
			(hide yes)
			(effects
				(font
					(size 1 1)
					(thickness 0.15)
				)
				(justify mirror)
			)
		)
		(property "Dielectric" "X5R"
			(at 394 271 0)
			(layer "B.Fab")
			(hide yes)
			(effects
				(font
					(size 1 1)
					(thickness 0.15)
				)
				(justify mirror)
			)
		)
		(property "License" "Apache-2.0"
			(at 394 271 0)
			(layer "B.Fab")
			(hide yes)
			(effects
				(font
					(size 1 1)
					(thickness 0.15)
				)
				(justify mirror)
			)
		)
		(property "MPN" "GRM155R61H104KE14D"
			(at 394 271 0)
			(layer "B.Fab")
			(hide yes)
			(effects
				(font
					(size 1 1)
					(thickness 0.15)
				)
				(justify mirror)
			)
		)
		(property "Manufacturer" "Murata"
			(at 394 271 0)
			(layer "B.Fab")
			(hide yes)
			(effects
				(font
					(size 1 1)
					(thickness 0.15)
				)
				(justify mirror)
			)
		)
		(property "Val" "100n"
			(at 394 271 0)
			(layer "B.Fab")
			(hide yes)
			(effects
				(font
					(size 1 1)
					(thickness 0.15)
				)
				(justify mirror)
			)
		)
		(property "Voltage" "50V"
			(at 394 271 0)
			(layer "B.Fab")
			(hide yes)
			(effects
				(font
					(size 1 1)
					(thickness 0.15)
				)
				(justify mirror)
			)
		)
		(sheetname "FPGA Bank 33 & 34")
		(sheetfile "fpga-bank-33-34.kicad_sch")
		(attr smd)
		(fp_rect
			(start -0.925 0.47)
			(end 0.925 -0.47)
			(stroke
				(width 0.05)
				(type default)
			)
			(fill no)
			(layer "B.CrtYd")
		)
		(fp_line
			(start 0.504 0.25)
			(end 0.504 -0.248)
			(stroke
				(width 0.15)
				(type solid)
			)
			(layer "B.Fab")
		)
		(fp_line
			(start 0.504 -0.248)
			(end -0.494 -0.248)
			(stroke
				(width 0.15)
				(type solid)
			)
			(layer "B.Fab")
		)
		(fp_line
			(start -0.494 0.25)
			(end 0.504 0.25)
			(stroke
				(width 0.15)
				(type solid)
			)
			(layer "B.Fab")
		)
		(fp_line
			(start -0.494 -0.248)
			(end -0.494 0.25)
			(stroke
				(width 0.15)
				(type solid)
			)
			(layer "B.Fab")
		)
		(pad "1" smd roundrect
			(at -0.48 0 180)
			(size 0.59 0.64)
			(layers "B.Cu" "B.Mask" "B.Paste")
			(roundrect_rratio 0.25)
			(net 1 "GND")
			(pintype "passive")
		)
		(pad "2" smd roundrect
			(at 0.48 0 180)
			(size 0.59 0.64)
			(layers "B.Cu" "B.Mask" "B.Paste")
			(roundrect_rratio 0.25)
			(net 26 "+1V8")
			(pintype "passive")
		)
	)
	(footprint "antmicro-footprints:R_0402_1005Metric"
		(layer "B.Cu")
		(at 238.899999 84.699999 90)
		(descr "Resistor SMD 0402")
		(tags "resistor SMD 0402")
		(property "Reference" "R125"
			(at -0.725001 0.425001 270)
			(layer "B.SilkS")
			(effects
				(font
					(size 0.7 0.7)
					(thickness 0.15)
				)
				(justify left bottom mirror)
			)
		)
		(property "Value" "R_100R_0402"
			(at 0 -1.4 270)
			(layer "B.Fab")
			(effects
				(font
					(size 0.7 0.7)
					(thickness 0.15)
				)
				(justify left bottom mirror)
			)
		)
		(property "Description" "SMD Chip Resistor, 100 ohm, ± 1%, 62.5 mW, 0402 [1005 Metric], Thick Film, General Purpose"
			(at 0 0 90)
			(layer "F.Fab")
			(hide yes)
			(effects
				(font
					(size 1.27 1.27)
					(thickness 0.15)
				)
			)
		)
		(property "Author" "Antmicro"
			(at 323.599998 -154.2 0)
			(layer "B.Fab")
			(hide yes)
			(effects
				(font
					(size 1 1)
					(thickness 0.15)
				)
				(justify mirror)
			)
		)
		(property "License" "Apache-2.0"
			(at 323.599998 -154.2 0)
			(layer "B.Fab")
			(hide yes)
			(effects
				(font
					(size 1 1)
					(thickness 0.15)
				)
				(justify mirror)
			)
		)
		(property "MPN" "CR0402-FX-1000GLF"
			(at 323.599998 -154.2 0)
			(layer "B.Fab")
			(hide yes)
			(effects
				(font
					(size 1 1)
					(thickness 0.15)
				)
				(justify mirror)
			)
		)
		(property "Manufacturer" "Bourns"
			(at 323.599998 -154.2 0)
			(layer "B.Fab")
			(hide yes)
			(effects
				(font
					(size 1 1)
					(thickness 0.15)
				)
				(justify mirror)
			)
		)
		(property "Tolerance" "1%"
			(at 323.599998 -154.2 0)
			(layer "B.Fab")
			(hide yes)
			(effects
				(font
					(size 1 1)
					(thickness 0.15)
				)
				(justify mirror)
			)
		)
		(property "Val" "100R"
			(at 323.599998 -154.2 0)
			(layer "B.Fab")
			(hide yes)
			(effects
				(font
					(size 1 1)
					(thickness 0.15)
				)
				(justify mirror)
			)
		)
		(sheetname "User GPIO + LED + button + DIP switch")
		(sheetfile "user-gpio.kicad_sch")
		(attr smd)
		(fp_rect
			(start -0.925 0.47)
			(end 0.925 -0.47)
			(stroke
				(width 0.05)
				(type default)
			)
			(fill no)
			(layer "B.CrtYd")
		)
		(fp_rect
			(start -0.5 0.25)
			(end 0.5 -0.25)
			(stroke
				(width 0.15)
				(type solid)
			)
			(fill no)
			(layer "B.Fab")
		)
		(pad "1" smd roundrect
			(at -0.48 0 90)
			(size 0.59 0.64)
			(layers "B.Cu" "B.Mask" "B.Paste")
			(roundrect_rratio 0.25)
			(net 470 "/FPGA Bank 12 & 13/PMOD_B.IO2")
			(pintype "passive")
		)
		(pad "2" smd roundrect
			(at 0.48 0 90)
			(size 0.59 0.64)
			(layers "B.Cu" "B.Mask" "B.Paste")
			(roundrect_rratio 0.25)
			(net 815 "/User GPIO + LED + button + DIP switch/PMOD_B_2")
			(pintype "passive")
		)
	)
	(footprint "antmicro-footprints:C_0402_1005Metric"
		(layer "B.Cu")
		(at 167.149999 148.924999 90)
		(descr "Capacitor SMD 0402")
		(tags "capacitor SMD 0402")
		(property "Reference" "C179"
			(at -0.775001 0.400001 270)
			(layer "B.SilkS")
			(effects
				(font
					(size 0.7 0.7)
					(thickness 0.15)
				)
				(justify left bottom mirror)
			)
		)
		(property "Value" "C_100n_0402"
			(at 0 -1.169 270)
			(layer "B.Fab")
			(effects
				(font
					(size 0.7 0.7)
					(thickness 0.15)
				)
				(justify left bottom mirror)
			)
		)
		(property "Description" "SMD Multilayer Ceramic Capacitor, 0.1 µF, 50 V, 0402 [1005 Metric], ± 10%, X5R, GRM Series"
			(at 0 0 90)
			(layer "F.Fab")
			(hide yes)
			(effects
				(font
					(size 1.27 1.27)
					(thickness 0.15)
				)
			)
		)
		(property "Author" "Antmicro"
			(at 316.074998 -18.225 0)
			(layer "B.Fab")
			(hide yes)
			(effects
				(font
					(size 1 1)
					(thickness 0.15)
				)
				(justify mirror)
			)
		)
		(property "Dielectric" "X5R"
			(at 316.074998 -18.225 0)
			(layer "B.Fab")
			(hide yes)
			(effects
				(font
					(size 1 1)
					(thickness 0.15)
				)
				(justify mirror)
			)
		)
		(property "License" "Apache-2.0"
			(at 316.074998 -18.225 0)
			(layer "B.Fab")
			(hide yes)
			(effects
				(font
					(size 1 1)
					(thickness 0.15)
				)
				(justify mirror)
			)
		)
		(property "MPN" "GRM155R61H104KE14D"
			(at 316.074998 -18.225 0)
			(layer "B.Fab")
			(hide yes)
			(effects
				(font
					(size 1 1)
					(thickness 0.15)
				)
				(justify mirror)
			)
		)
		(property "Manufacturer" "Murata"
			(at 316.074998 -18.225 0)
			(layer "B.Fab")
			(hide yes)
			(effects
				(font
					(size 1 1)
					(thickness 0.15)
				)
				(justify mirror)
			)
		)
		(property "Val" "100n"
			(at 316.074998 -18.225 0)
			(layer "B.Fab")
			(hide yes)
			(effects
				(font
					(size 1 1)
					(thickness 0.15)
				)
				(justify mirror)
			)
		)
		(property "Voltage" "50V"
			(at 316.074998 -18.225 0)
			(layer "B.Fab")
			(hide yes)
			(effects
				(font
					(size 1 1)
					(thickness 0.15)
				)
				(justify mirror)
			)
		)
		(sheetname "DRAM + SRAM")
		(sheetfile "ram.kicad_sch")
		(attr smd)
		(fp_rect
			(start -0.925 0.47)
			(end 0.925 -0.47)
			(stroke
				(width 0.05)
				(type default)
			)
			(fill no)
			(layer "B.CrtYd")
		)
		(fp_line
			(start 0.504 -0.248)
			(end -0.494 -0.248)
			(stroke
				(width 0.15)
				(type solid)
			)
			(layer "B.Fab")
		)
		(fp_line
			(start -0.494 -0.248)
			(end -0.494 0.25)
			(stroke
				(width 0.15)
				(type solid)
			)
			(layer "B.Fab")
		)
		(fp_line
			(start 0.504 0.25)
			(end 0.504 -0.248)
			(stroke
				(width 0.15)
				(type solid)
			)
			(layer "B.Fab")
		)
		(fp_line
			(start -0.494 0.25)
			(end 0.504 0.25)
			(stroke
				(width 0.15)
				(type solid)
			)
			(layer "B.Fab")
		)
		(pad "1" smd roundrect
			(at -0.48 0 90)
			(size 0.59 0.64)
			(layers "B.Cu" "B.Mask" "B.Paste")
			(roundrect_rratio 0.25)
			(net 1 "GND")
			(pintype "passive")
		)
		(pad "2" smd roundrect
			(at 0.48 0 90)
			(size 0.59 0.64)
			(layers "B.Cu" "B.Mask" "B.Paste")
			(roundrect_rratio 0.25)
			(net 25 "+1V35")
			(pintype "passive")
		)
	)
	(footprint "antmicro-footprints:TP_1206_SMD_RCW-0C"
		(layer "B.Cu")
		(at 214.66 172.89 180)
		(property "Reference" "TP10"
			(at -1.165 1.365 0)
			(layer "B.SilkS")
			(effects
				(font
					(size 0.7 0.7)
					(thickness 0.15)
				)
				(justify left bottom mirror)
			)
		)
		(property "Value" "TP_1206_SMD_RCW-0C"
			(at -4.68 -2.25 0)
			(layer "B.Fab")
			(effects
				(font
					(size 0.7 0.7)
					(thickness 0.15)
				)
				(justify left bottom mirror)
			)
		)
		(property "Description" "Circuit Probe Pad, SMD, Test Point, 1206"
			(at 0 0 180)
			(layer "F.Fab")
			(hide yes)
			(effects
				(font
					(size 1.27 1.27)
					(thickness 0.15)
				)
			)
		)
		(property "Author" "Antmicro"
			(at 429.32 345.78 0)
			(layer "B.Fab")
			(hide yes)
			(effects
				(font
					(size 1 1)
					(thickness 0.15)
				)
				(justify mirror)
			)
		)
		(property "License" "Apache-2.0"
			(at 429.32 345.78 0)
			(layer "B.Fab")
			(hide yes)
			(effects
				(font
					(size 1 1)
					(thickness 0.15)
				)
				(justify mirror)
			)
		)
		(property "MPN" "RCW-0C"
			(at 429.32 345.78 0)
			(layer "B.Fab")
			(hide yes)
			(effects
				(font
					(size 1 1)
					(thickness 0.15)
				)
				(justify mirror)
			)
		)
		(property "Manufacturer" "TE Connectivity"
			(at 429.32 345.78 0)
			(layer "B.Fab")
			(hide yes)
			(effects
				(font
					(size 1 1)
					(thickness 0.15)
				)
				(justify mirror)
			)
		)
		(sheetfile "k410t-devboard.kicad_sch")
		(attr smd)
		(fp_line
			(start 1.78 0.981)
			(end 1.78 0.479)
			(stroke
				(width 0.15)
				(type solid)
			)
			(layer "B.SilkS")
		)
		(fp_line
			(start 1.78 0.981)
			(end 1.281 0.981)
			(stroke
				(width 0.15)
				(type solid)
			)
			(layer "B.SilkS")
		)
		(fp_line
			(start 1.78 -0.982)
			(end 1.78 -0.482)
			(stroke
				(width 0.15)
				(type solid)
			)
			(layer "B.SilkS")
		)
		(fp_line
			(start 1.78 -0.982)
			(end 1.281 -0.982)
			(stroke
				(width 0.15)
				(type solid)
			)
			(layer "B.SilkS")
		)
		(fp_line
			(start -1.779 0.981)
			(end -1.279 0.981)
			(stroke
				(width 0.15)
				(type solid)
			)
			(layer "B.SilkS")
		)
		(fp_line
			(start -1.779 0.981)
			(end -1.779 0.479)
			(stroke
				(width 0.15)
				(type solid)
			)
			(layer "B.SilkS")
		)
		(fp_line
			(start -1.779 -0.482)
			(end -1.779 -0.98)
			(stroke
				(width 0.15)
				(type solid)
			)
			(layer "B.SilkS")
		)
		(fp_line
			(start -1.779 -0.98)
			(end -1.279 -0.98)
			(stroke
				(width 0.15)
				(type solid)
			)
			(layer "B.SilkS")
		)
		(fp_rect
			(start -2.101 1.314)
			(end 2.1 -1.312)
			(stroke
				(width 0.05)
				(type solid)
			)
			(fill no)
			(layer "B.CrtYd")
		)
		(fp_rect
			(start -1.601 0.814)
			(end 1.6 -0.812)
			(stroke
				(width 0.15)
				(type solid)
			)
			(fill no)
			(layer "B.Fab")
		)
		(pad "1" smd rect
			(at 0 0 180)
			(size 3.4 1.8)
			(layers "B.Cu" "B.Mask" "B.Paste")
			(net 1 "GND")
			(pinfunction "1")
			(pintype "passive")
		)
	)
)
